# S9S_MB_2U (Grand Teton) — schematic netlist excerpt (pin names and nets, part order shuffled) for the footprints in the layout excerpt that follows; sources: Cadence DE-HDL packaged netlist, KiCad conversion of 03242023_DA0F0TMBIJ0_F0T_Motherboard_J_brd_V01_OCP.brd

C2389  Q_CAP  100NF 50V 10% EMPTY  pkg C0402  page 306 : A = HSC_OC_VOL ; B = GND
R3641  Q_RES  10K 1% CHIP  pkg 0402LF  page 208 : A = P3V3_AUX ; B = CK440Q_OE_4

(kicad_pcb
	(version 20260206)
	(generator "pcbnew")
	(generator_version "10.0")
	(general
		(thickness 1.6)
		(legacy_teardrops no)
	)
	(paper "A4")
	(title_block
		(title "03242023_DA0F0TMBIJ0_F0T_Motherboard_J_brd_V01_OCP.brd")
		(comment 1 "Grand Teton / footprints 2278-2279 of 6105")
	)
	(layers
		(0 "F.Cu" signal "TOP")
		(4 "In1.Cu" signal "GND")
		(6 "In2.Cu" signal "IN1")
		(8 "In3.Cu" signal "GND1")
		(10 "In4.Cu" signal "IN2")
		(12 "In5.Cu" signal "GND2")
		(14 "In6.Cu" signal "IN3")
		(16 "In7.Cu" signal "GND3")
		(18 "In8.Cu" signal "VCC")
		(20 "In9.Cu" signal "VCC1")
		(22 "In10.Cu" signal "GND4")
		(24 "In11.Cu" signal "IN4")
		(26 "In12.Cu" signal "GND5")
		(28 "In13.Cu" signal "IN5")
		(30 "In14.Cu" signal "GND6")
		(32 "In15.Cu" signal "IN6")
		(34 "In16.Cu" signal "GND7")
		(2 "B.Cu" signal "BOTTOM")
		(9 "F.Adhes" user "F.Adhesive")
		(11 "B.Adhes" user "B.Adhesive")
		(13 "F.Paste" user "Package Geometry/Pastemask Top")
		(15 "B.Paste" user "Package Geometry/Pastemask Bottom")
		(5 "F.SilkS" user "Ref Des/Silkscreen Top")
		(7 "B.SilkS" user "Ref Des/Silkscreen Bottom")
		(1 "F.Mask" user "Board Geometry/Soldermask Top")
		(3 "B.Mask" user "Board Geometry/Soldermask Bottom")
		(17 "Dwgs.User" user "User.Drawings")
		(19 "Cmts.User" user "User.Comments")
		(21 "Eco1.User" user "User.Eco1")
		(23 "Eco2.User" user "User.Eco2")
		(25 "Edge.Cuts" user "Board Geometry/Outline")
		(27 "Margin" user)
		(31 "F.CrtYd" user "Package Geometry/Place Bound Top")
		(29 "B.CrtYd" user "Package Geometry/Place Bound Bottom")
		(35 "F.Fab" user "Ref Des/Assembly Top")
		(33 "B.Fab" user "Ref Des/Assembly Bottom")
	)
	(footprint ""
		(layer "F.Cu")
		(at 182.82158 -411.20568 -90)
		(property "Reference" "C2389"
			(at 0 0 270)
			(layer "F.SilkS")
			(hide yes)
			(effects
				(font
					(size 1.27 1.27)
				)
			)
		)
		(property "Value" ""
			(at 0 0 270)
			(layer "F.Fab")
			(effects
				(font
					(size 1.27 1.27)
				)
			)
		)
		(duplicate_pad_numbers_are_jumpers no)
		(fp_line
			(start -0.7874 0.4064)
			(end -0.7874 -0.4064)
			(stroke
				(width 0.1524)
				(type default)
			)
			(layer "F.SilkS")
		)
		(fp_line
			(start 0.7874 0.4064)
			(end -0.7874 0.4064)
			(stroke
				(width 0.1524)
				(type default)
			)
			(layer "F.SilkS")
		)
		(fp_line
			(start -0.7874 -0.4064)
			(end 0.7874 -0.4064)
			(stroke
				(width 0.1524)
				(type default)
			)
			(layer "F.SilkS")
		)
		(fp_line
			(start 0.7874 -0.4064)
			(end 0.7874 0.4064)
			(stroke
				(width 0.1524)
				(type default)
			)
			(layer "F.SilkS")
		)
		(fp_line
			(start -0.67945 0.3048)
			(end -0.67945 -0.305054)
			(stroke
				(width 0.1)
				(type default)
			)
			(layer "F.Fab")
		)
		(fp_line
			(start -0.12065 0.3048)
			(end -0.67945 0.3048)
			(stroke
				(width 0.1)
				(type default)
			)
			(layer "F.Fab")
		)
		(fp_line
			(start 0.120396 0.3048)
			(end 0.120396 0.2794)
			(stroke
				(width 0.1)
				(type default)
			)
			(layer "F.Fab")
		)
		(fp_line
			(start 0.67945 0.3048)
			(end 0.120396 0.3048)
			(stroke
				(width 0.1)
				(type default)
			)
			(layer "F.Fab")
		)
		(fp_line
			(start -0.12065 0.2794)
			(end -0.12065 0.3048)
			(stroke
				(width 0.1)
				(type default)
			)
			(layer "F.Fab")
		)
		(fp_line
			(start 0.120396 0.2794)
			(end -0.12065 0.2794)
			(stroke
				(width 0.1)
				(type default)
			)
			(layer "F.Fab")
		)
		(fp_line
			(start -0.12065 -0.2794)
			(end 0.12065 -0.2794)
			(stroke
				(width 0.1)
				(type default)
			)
			(layer "F.Fab")
		)
		(fp_line
			(start 0.12065 -0.2794)
			(end 0.12065 -0.3048)
			(stroke
				(width 0.1)
				(type default)
			)
			(layer "F.Fab")
		)
		(fp_line
			(start 0.12065 -0.3048)
			(end 0.67945 -0.3048)
			(stroke
				(width 0.1)
				(type default)
			)
			(layer "F.Fab")
		)
		(fp_line
			(start 0.67945 -0.3048)
			(end 0.67945 0.3048)
			(stroke
				(width 0.1)
				(type default)
			)
			(layer "F.Fab")
		)
		(fp_line
			(start -0.67945 -0.305054)
			(end -0.12065 -0.305054)
			(stroke
				(width 0.1)
				(type default)
			)
			(layer "F.Fab")
		)
		(fp_line
			(start -0.12065 -0.305054)
			(end -0.12065 -0.2794)
			(stroke
				(width 0.1)
				(type default)
			)
			(layer "F.Fab")
		)
		(pad "1" smd circle
			(at -0.40005 0 270)
			(size 0 0)
			(layers "F.Cu" "F.Mask" "F.Paste")
			(net "HSC_OC_VOL")
		)
		(pad "2" smd circle
			(at 0.40005 0 270)
			(size 0 0)
			(layers "F.Cu" "F.Mask" "F.Paste")
			(net "GND")
		)
	)
	(footprint ""
		(layer "F.Cu")
		(at 256.473452 -92.292424)
		(property "Reference" "R3641"
			(at 0 0 0)
			(layer "F.SilkS")
			(hide yes)
			(effects
				(font
					(size 1.27 1.27)
				)
			)
		)
		(property "Value" ""
			(at 0 0 0)
			(layer "F.Fab")
			(effects
				(font
					(size 1.27 1.27)
				)
			)
		)
		(duplicate_pad_numbers_are_jumpers no)
		(fp_line
			(start -0.7874 -0.4064)
			(end 0.7874 -0.4064)
			(stroke
				(width 0.1524)
				(type default)
			)
			(layer "F.SilkS")
		)
		(fp_line
			(start -0.7874 0.4064)
			(end -0.7874 -0.4064)
			(stroke
				(width 0.1524)
				(type default)
			)
			(layer "F.SilkS")
		)
		(fp_line
			(start 0.7874 -0.4064)
			(end 0.7874 0.4064)
			(stroke
				(width 0.1524)
				(type default)
			)
			(layer "F.SilkS")
		)
		(fp_line
			(start 0.7874 0.4064)
			(end -0.7874 0.4064)
			(stroke
				(width 0.1524)
				(type default)
			)
			(layer "F.SilkS")
		)
		(fp_line
			(start -0.67945 -0.305054)
			(end -0.12065 -0.305054)
			(stroke
				(width 0.1)
				(type default)
			)
			(layer "F.Fab")
		)
		(fp_line
			(start -0.67945 0.3048)
			(end -0.67945 -0.305054)
			(stroke
				(width 0.1)
				(type default)
			)
			(layer "F.Fab")
		)
		(fp_line
			(start -0.12065 -0.305054)
			(end -0.12065 -0.2794)
			(stroke
				(width 0.1)
				(type default)
			)
			(layer "F.Fab")
		)
		(fp_line
			(start -0.12065 -0.2794)
			(end 0.12065 -0.2794)
			(stroke
				(width 0.1)
				(type default)
			)
			(layer "F.Fab")
		)
		(fp_line
			(start -0.12065 0.2794)
			(end -0.12065 0.3048)
			(stroke
				(width 0.1)
				(type default)
			)
			(layer "F.Fab")
		)
		(fp_line
			(start -0.12065 0.3048)
			(end -0.67945 0.3048)
			(stroke
				(width 0.1)
				(type default)
			)
			(layer "F.Fab")
		)
		(fp_line
			(start 0.120396 0.2794)
			(end -0.12065 0.2794)
			(stroke
				(width 0.1)
				(type default)
			)
			(layer "F.Fab")
		)
		(fp_line
			(start 0.120396 0.3048)
			(end 0.120396 0.2794)
			(stroke
				(width 0.1)
				(type default)
			)
			(layer "F.Fab")
		)
		(fp_line
			(start 0.12065 -0.3048)
			(end 0.67945 -0.3048)
			(stroke
				(width 0.1)
				(type default)
			)
			(layer "F.Fab")
		)
		(fp_line
			(start 0.12065 -0.2794)
			(end 0.12065 -0.3048)
			(stroke
				(width 0.1)
				(type default)
			)
			(layer "F.Fab")
		)
		(fp_line
			(start 0.67945 -0.3048)
			(end 0.67945 0.3048)
			(stroke
				(width 0.1)
				(type default)
			)
			(layer "F.Fab")
		)
		(fp_line
			(start 0.67945 0.3048)
			(end 0.120396 0.3048)
			(stroke
				(width 0.1)
				(type default)
			)
			(layer "F.Fab")
		)
		(pad "1" smd circle
			(at -0.40005 0)
			(size 0 0)
			(layers "F.Cu" "F.Mask" "F.Paste")
			(net "P3V3_AUX")
		)
		(pad "2" smd circle
			(at 0.40005 0)
			(size 0 0)
			(layers "F.Cu" "F.Mask" "F.Paste")
			(net "CK440Q_OE_4")
		)
	)
)
